# T6G (Grand Teton) — schematic netlist excerpt (pin names and nets, part order shuffled) for the footprints in the layout excerpt that follows; sources: Cadence DE-HDL packaged netlist, KiCad conversion of 04192023_DAF0TMB3IC0_F0TG_MB_C_brd_V02_OCP.brd

X5  TP_TDR_4P_FTS  TP_TDR_4P_DIP EMPTY  pkg TH  page 260
  S1  = TDR_DIFF_80_IN4_DP
  P1  = T1_GND
  P2  = T1_GND
  S2  = TDR_DIFF_80_IN4_DN

C6627  Q_CAP_DIFFBUS  DIFF BUS_0.22UF 6.3V 20% X6S  pkg C0201  page 308 : \1\ = P5E_CPU0_P3_TX_BUF_C_DP<15> ; \2\ = P5E_CPU0_P3_TX_BUF_DP<15>

(kicad_pcb
	(version 20260206)
	(generator "pcbnew")
	(generator_version "10.0")
	(general
		(thickness 1.6)
		(legacy_teardrops no)
	)
	(paper "A4")
	(title_block
		(title "04192023_DAF0TMB3IC0_F0TG_MB_C_brd_V02_OCP.brd")
		(comment 1 "Grand Teton / footprints 8332-8333 of 8354")
	)
	(layers
		(0 "F.Cu" signal "TOP")
		(4 "In1.Cu" signal "GND")
		(6 "In2.Cu" signal "IN1")
		(8 "In3.Cu" signal "GND1")
		(10 "In4.Cu" signal "IN2")
		(12 "In5.Cu" signal "GND2")
		(14 "In6.Cu" signal "IN3")
		(16 "In7.Cu" signal "GND3")
		(18 "In8.Cu" signal "VCC")
		(20 "In9.Cu" signal "VCC1")
		(22 "In10.Cu" signal "GND4")
		(24 "In11.Cu" signal "IN4")
		(26 "In12.Cu" signal "GND5")
		(28 "In13.Cu" signal "IN5")
		(30 "In14.Cu" signal "GND6")
		(32 "In15.Cu" signal "IN6")
		(34 "In16.Cu" signal "GND7")
		(2 "B.Cu" signal "BOTTOM")
		(9 "F.Adhes" user "F.Adhesive")
		(11 "B.Adhes" user "B.Adhesive")
		(13 "F.Paste" user "Package Geometry/Pastemask Top")
		(15 "B.Paste" user "Package Geometry/Pastemask Bottom")
		(5 "F.SilkS" user "Ref Des/Silkscreen Top")
		(7 "B.SilkS" user "Ref Des/Silkscreen Bottom")
		(1 "F.Mask" user "Board Geometry/Soldermask Top")
		(3 "B.Mask" user "Board Geometry/Soldermask Bottom")
		(17 "Dwgs.User" user "User.Drawings")
		(19 "Cmts.User" user "User.Comments")
		(21 "Eco1.User" user "User.Eco1")
		(23 "Eco2.User" user "User.Eco2")
		(25 "Edge.Cuts" user "Board Geometry/Outline")
		(27 "Margin" user)
		(31 "F.CrtYd" user "Package Geometry/Place Bound Top")
		(29 "B.CrtYd" user "Package Geometry/Place Bound Bottom")
		(35 "F.Fab" user "Ref Des/Assembly Top")
		(33 "B.Fab" user "Ref Des/Assembly Bottom")
	)
	(footprint ""
		(layer "B.Cu")
		(at 419.263322 -416.899344 90)
		(property "Reference" "C6627"
			(at 0 0 90)
			(layer "B.SilkS")
			(hide yes)
			(effects
				(font
					(size 1.27 1.27)
				)
				(justify mirror)
			)
		)
		(property "Value" ""
			(at 0 0 90)
			(layer "B.Fab")
			(effects
				(font
					(size 1.27 1.27)
				)
				(justify mirror)
			)
		)
		(duplicate_pad_numbers_are_jumpers no)
		(fp_line
			(start 0.299974 -0.150114)
			(end -0.299974 -0.150114)
			(stroke
				(width 0.1)
				(type default)
			)
			(layer "B.Fab")
		)
		(fp_line
			(start -0.299974 -0.150114)
			(end -0.299974 0.150114)
			(stroke
				(width 0.1)
				(type default)
			)
			(layer "B.Fab")
		)
		(fp_line
			(start 0.299974 0.150114)
			(end 0.299974 -0.150114)
			(stroke
				(width 0.1)
				(type default)
			)
			(layer "B.Fab")
		)
		(fp_line
			(start -0.299974 0.150114)
			(end 0.299974 0.150114)
			(stroke
				(width 0.1)
				(type default)
			)
			(layer "B.Fab")
		)
		(pad "1" smd rect
			(at 0.2667 0 270)
			(size 0.3048 0.381)
			(layers "B.Cu" "B.Mask" "B.Paste")
			(net "P5E_CPU0_P3_TX_BUF_C_DP<15>")
		)
		(pad "2" smd rect
			(at -0.2667 0 270)
			(size 0.3048 0.381)
			(layers "B.Cu" "B.Mask" "B.Paste")
			(net "P5E_CPU0_P3_TX_BUF_DP<15>")
		)
	)
	(footprint ""
		(layer "B.Cu")
		(at 520.044426 -147.962874 90)
		(property "Reference" "X5"
			(at 0.989076 2.861564 270)
			(unlocked yes)
			(layer "B.SilkS")
			(effects
				(font
					(size 0.7874 0.5842)
					(thickness 0.1524)
				)
				(justify left mirror)
			)
		)
		(property "Value" ""
			(at 0 0 90)
			(layer "B.Fab")
			(effects
				(font
					(size 1.27 1.27)
				)
				(justify mirror)
			)
		)
		(property "Device Type" "TP_TDR_4P_FTS_TH-TP_TDR_4P_DIP,EMPTY,TP15"
			(at -1.30175 1.27 0)
			(unlocked yes)
			(layer "B.Fab")
			(hide yes)
			(effects
				(font
					(size 0.635 0.4064)
					(thickness 0.1524)
				)
				(justify mirror)
			)
		)
		(property "User Part Number" "N_A"
			(at -1.30175 1.27 0)
			(unlocked yes)
			(layer "Cmts.User")
			(hide yes)
			(effects
				(font
					(size 0.635 0.4064)
					(thickness 0.1524)
				)
				(justify mirror)
			)
		)
		(duplicate_pad_numbers_are_jumpers no)
		(fp_line
			(start 0 -1.27)
			(end 0 -0.635)
			(stroke
				(width 0.1524)
				(type default)
			)
			(layer "B.SilkS")
		)
		(fp_line
			(start -2.54 -1.27)
			(end 0 -1.27)
			(stroke
				(width 0.1524)
				(type default)
			)
			(layer "B.SilkS")
		)
		(fp_line
			(start -2.54 -1.1303)
			(end -2.54 -1.27)
			(stroke
				(width 0.1524)
				(type default)
			)
			(layer "B.SilkS")
		)
		(fp_line
			(start 0 0.635)
			(end 0 1.905)
			(stroke
				(width 0.1524)
				(type default)
			)
			(layer "B.SilkS")
		)
		(fp_line
			(start -2.54 1.4097)
			(end -2.54 1.1303)
			(stroke
				(width 0.1524)
				(type default)
			)
			(layer "B.SilkS")
		)
		(fp_line
			(start 0 3.175)
			(end 0 3.81)
			(stroke
				(width 0.1524)
				(type default)
			)
			(layer "B.SilkS")
		)
		(fp_line
			(start 0 3.81)
			(end -2.54 3.81)
			(stroke
				(width 0.1524)
				(type default)
			)
			(layer "B.SilkS")
		)
		(fp_line
			(start -2.54 3.81)
			(end -2.54 3.6703)
			(stroke
				(width 0.1524)
				(type default)
			)
			(layer "B.SilkS")
		)
		(fp_poly
			(pts
				(xy 2.285746 -0.762) (xy 2.285746 0.762) (xy 0.761746 0)
			)
			(stroke
				(width 0)
				(type default)
			)
			(fill yes)
			(layer "B.SilkS")
		)
		(fp_line
			(start 0 -1.27)
			(end 0 3.81)
			(stroke
				(width 0.1)
				(type default)
			)
			(layer "B.Fab")
		)
		(fp_line
			(start -2.54 -1.27)
			(end 0 -1.27)
			(stroke
				(width 0.1)
				(type default)
			)
			(layer "B.Fab")
		)
		(fp_line
			(start 0 3.81)
			(end -2.54 3.81)
			(stroke
				(width 0.1)
				(type default)
			)
			(layer "B.Fab")
		)
		(fp_line
			(start -2.54 3.81)
			(end -2.54 -1.27)
			(stroke
				(width 0.1)
				(type default)
			)
			(layer "B.Fab")
		)
		(fp_poly
			(pts
				(xy 0.761746 0) (xy 2.285746 -0.762) (xy 2.285746 0.762)
			)
			(stroke
				(width 0)
				(type default)
			)
			(fill yes)
			(layer "B.Fab")
		)
		(pad "1" thru_hole circle
			(at 0 0 270)
			(size 1.0033 1.0033)
			(drill 0.249936)
			(layers "*.Cu" "*.Mask")
			(remove_unused_layers no)
			(net "TDR_DIFF_80_IN4_DP")
			(clearance 0.10795)
			(padstack
				(mode front_inner_back)
				(layer "Inner"
					(shape circle)
					(size 0.8001 0.8001)
					(clearance 0.1524)
				)
				(layer "B.Cu"
					(shape circle)
					(size 1.0033 1.0033)
					(thermal_gap 0.10795)
					(clearance 0.10795)
				)
			)
		)
		(pad "2" thru_hole circle
			(at -2.54 0 270)
			(size 1.9939 1.9939)
			(drill 0.249936)
			(layers "*.Cu" "*.Mask")
			(remove_unused_layers no)
			(net "T1_GND")
			(clearance 0.10795)
			(padstack
				(mode front_inner_back)
				(layer "Inner"
					(shape circle)
					(size 0.8001 0.8001)
					(clearance 0.1524)
				)
				(layer "B.Cu"
					(shape circle)
					(size 1.9939 1.9939)
					(thermal_gap 0.10795)
					(clearance 0.10795)
				)
			)
		)
		(pad "3" thru_hole circle
			(at -2.54 2.54 270)
			(size 1.9939 1.9939)
			(drill 0.249936)
			(layers "*.Cu" "*.Mask")
			(remove_unused_layers no)
			(net "T1_GND")
			(clearance 0.10795)
			(padstack
				(mode front_inner_back)
				(layer "Inner"
					(shape circle)
					(size 0.8001 0.8001)
					(clearance 0.1524)
				)
				(layer "B.Cu"
					(shape circle)
					(size 1.9939 1.9939)
					(thermal_gap 0.10795)
					(clearance 0.10795)
				)
			)
		)
		(pad "4" thru_hole circle
			(at 0 2.54 270)
			(size 1.0033 1.0033)
			(drill 0.249936)
			(layers "*.Cu" "*.Mask")
			(remove_unused_layers no)
			(net "TDR_DIFF_80_IN4_DN")
			(clearance 0.10795)
			(padstack
				(mode front_inner_back)
				(layer "Inner"
					(shape circle)
					(size 0.8001 0.8001)
					(clearance 0.1524)
				)
				(layer "B.Cu"
					(shape circle)
					(size 1.0033 1.0033)
					(thermal_gap 0.10795)
					(clearance 0.10795)
				)
			)
		)
	)
)
